(kicad_pcb
	(version 20260206)
	(generator "pcbnew")
	(generator_version "10.0")
	(general
		(thickness 1.6)
		(legacy_teardrops no)
	)
	(paper "A4")
	(title_block
		(title "peb — Lightning_PEB_BRD.brd")
		(comment 1 "Lightning (Wiwynn / Facebook NVMe JBOF) / footprints 2093-2099 of 2563")
	)
	(layers
		(0 "F.Cu" signal "TOP")
		(4 "In1.Cu" signal "L2GND")
		(6 "In2.Cu" signal "L3")
		(8 "In3.Cu" signal "L4VCC")
		(10 "In4.Cu" signal "L5VCC")
		(12 "In5.Cu" signal "L6")
		(14 "In6.Cu" signal "L7GND")
		(2 "B.Cu" signal "BOTTOM")
		(9 "F.Adhes" user "F.Adhesive")
		(11 "B.Adhes" user "B.Adhesive")
		(13 "F.Paste" user "Package Geometry/Pastemask Top")
		(15 "B.Paste" user "Package Geometry/Pastemask Bottom")
		(5 "F.SilkS" user "Ref Des/Silkscreen Top")
		(7 "B.SilkS" user "Ref Des/Silkscreen Bottom")
		(1 "F.Mask" user "Board Geometry/Soldermask Top")
		(3 "B.Mask" user "Board Geometry/Soldermask Bottom")
		(17 "Dwgs.User" user "User.Drawings")
		(19 "Cmts.User" user "User.Comments")
		(21 "Eco1.User" user "User.Eco1")
		(23 "Eco2.User" user "User.Eco2")
		(25 "Edge.Cuts" user "Board Geometry/Outline")
		(27 "Margin" user)
		(31 "F.CrtYd" user "Package Geometry/Place Bound Top")
		(29 "B.CrtYd" user "Package Geometry/Place Bound Bottom")
		(35 "F.Fab" user "Ref Des/Assembly Top")
		(33 "B.Fab" user "Ref Des/Assembly Bottom")
	)
	(footprint ""
		(layer "B.Cu")
		(at 223.57334 -201.39914 -90)
		(property "Reference" "R3225"
			(at 0 0 90)
			(layer "B.SilkS")
			(hide yes)
			(effects
				(font
					(size 1.27 1.27)
				)
				(justify mirror)
			)
		)
		(property "Value" "0R2J-2-GP"
			(at -0.064008 -3.993896 270)
			(unlocked yes)
			(layer "B.Fab")
			(hide yes)
			(effects
				(font
					(size 1.016 1.016)
					(thickness 0.1524)
				)
				(justify mirror)
			)
		)
		(property "Device Type" "R402H16"
			(at -0.064008 -5.517896 270)
			(unlocked yes)
			(layer "B.Fab")
			(hide yes)
			(effects
				(font
					(size 1.016 1.016)
					(thickness 0.1524)
				)
				(justify mirror)
			)
		)
		(duplicate_pad_numbers_are_jumpers no)
		(fp_line
			(start -0.508 -0.9398)
			(end 0.508 -0.9398)
			(stroke
				(width 0.1524)
				(type default)
			)
			(layer "B.SilkS")
		)
		(fp_line
			(start 0.508 -0.9398)
			(end 0.508 0.9398)
			(stroke
				(width 0.1524)
				(type default)
			)
			(layer "B.SilkS")
		)
		(fp_rect
			(start 0.508 0.9398)
			(end -0.508 -0.9398)
			(stroke
				(width 0)
				(type default)
			)
			(fill no)
			(layer "B.CrtYd")
		)
		(fp_rect
			(start 0.508 0.9398)
			(end -0.508 -0.9398)
			(stroke
				(width 0)
				(type default)
			)
			(fill no)
			(layer "B.Fab")
		)
		(pad "1" smd custom
			(at 0 -0.4445 90)
			(size 0.1397 0.1397)
			(layers "B.Cu" "B.Mask" "B.Paste")
			(net "SSD_PERST#8")
			(options
				(clearance outline)
				(anchor circle)
			)
			(primitives
				(gr_poly
					(pts
						(arc
							(start -0.1778 0.2794)
							(mid -0.249642 0.249642)
							(end -0.2794 0.1778)
						)
						(arc
							(start -0.2794 -0.1778)
							(mid -0.249642 -0.249642)
							(end -0.1778 -0.2794)
						)
						(arc
							(start 0.1778 -0.2794)
							(mid 0.249642 -0.249642)
							(end 0.2794 -0.1778)
						)
						(arc
							(start 0.2794 0.1778)
							(mid 0.249642 0.249642)
							(end 0.1778 0.2794)
						)
					)
					(width 0)
					(fill yes)
				)
			)
		)
		(pad "2" smd custom
			(at 0 0.4445 90)
			(size 0.1397 0.1397)
			(layers "B.Cu" "B.Mask" "B.Paste")
			(net "SSD_PERST#0_B8")
			(options
				(clearance outline)
				(anchor circle)
			)
			(primitives
				(gr_poly
					(pts
						(arc
							(start -0.1778 0.2794)
							(mid -0.249642 0.249642)
							(end -0.2794 0.1778)
						)
						(arc
							(start -0.2794 -0.1778)
							(mid -0.249642 -0.249642)
							(end -0.1778 -0.2794)
						)
						(arc
							(start 0.1778 -0.2794)
							(mid 0.249642 -0.249642)
							(end 0.2794 -0.1778)
						)
						(arc
							(start 0.2794 0.1778)
							(mid 0.249642 0.249642)
							(end 0.1778 0.2794)
						)
					)
					(width 0)
					(fill yes)
				)
			)
		)
	)
	(footprint ""
		(layer "B.Cu")
		(at 215.702388 -197.096126)
		(property "Reference" "U77"
			(at 0 0 0)
			(layer "B.SilkS")
			(hide yes)
			(effects
				(font
					(size 1.27 1.27)
				)
				(justify mirror)
			)
		)
		(property "Value" "SN74LVC1G08DCKR-GP"
			(at 2.3368 -8.6868 0)
			(unlocked yes)
			(layer "B.Fab")
			(hide yes)
			(effects
				(font
					(size 1.016 1.016)
					(thickness 0.1524)
				)
				(justify mirror)
			)
		)
		(property "Device Type" "SC70-5H44"
			(at 2.3114 -10.414 0)
			(unlocked yes)
			(layer "B.Fab")
			(hide yes)
			(effects
				(font
					(size 1.016 1.016)
					(thickness 0.1524)
				)
				(justify mirror)
			)
		)
		(duplicate_pad_numbers_are_jumpers no)
		(fp_line
			(start -1.3843 -1.8034)
			(end -1.3843 -1.1176)
			(stroke
				(width 0.3302)
				(type default)
			)
			(layer "B.SilkS")
		)
		(fp_line
			(start -1.27 -1.7018)
			(end -1.27 1.7018)
			(stroke
				(width 0.1524)
				(type default)
			)
			(layer "B.SilkS")
		)
		(fp_line
			(start -1.27 1.7018)
			(end 1.27 1.7018)
			(stroke
				(width 0.1524)
				(type default)
			)
			(layer "B.SilkS")
		)
		(fp_line
			(start -0.6604 -1.8034)
			(end -1.3843 -1.8034)
			(stroke
				(width 0.3302)
				(type default)
			)
			(layer "B.SilkS")
		)
		(fp_line
			(start 1.27 -1.7018)
			(end -1.27 -1.7018)
			(stroke
				(width 0.1524)
				(type default)
			)
			(layer "B.SilkS")
		)
		(fp_line
			(start 1.27 1.7018)
			(end 1.27 -1.7018)
			(stroke
				(width 0.1524)
				(type default)
			)
			(layer "B.SilkS")
		)
		(fp_rect
			(start 1.524 1.9558)
			(end -1.524 -1.9558)
			(stroke
				(width 0)
				(type default)
			)
			(fill no)
			(layer "B.CrtYd")
		)
		(fp_poly
			(pts
				(xy 1.524 -1.9558) (xy -1.524 -1.9558) (xy -1.524 1.9558) (xy 1.524 1.9558)
			)
			(stroke
				(width 0)
				(type default)
			)
			(fill no)
			(layer "B.Fab")
		)
		(pad "1" smd rect
			(at -0.65024 -0.8255 180)
			(size 0.4064 1.2192)
			(layers "B.Cu" "B.Mask" "B.Paste")
			(net "BMC_SSD_RST#0_A13")
		)
		(pad "2" smd rect
			(at 0 -0.8255 180)
			(size 0.4064 1.2192)
			(layers "B.Cu" "B.Mask" "B.Paste")
			(net "SSD_PERST#0_B13")
		)
		(pad "3" smd rect
			(at 0.65024 -0.8255 180)
			(size 0.4064 1.2192)
			(layers "B.Cu" "B.Mask" "B.Paste")
			(net "GND")
		)
		(pad "4" smd rect
			(at 0.65024 0.8255 180)
			(size 0.4064 1.2192)
			(layers "B.Cu" "B.Mask" "B.Paste")
			(net "SSD_PERST_Y13")
		)
		(pad "5" smd rect
			(at -0.65024 0.8255 180)
			(size 0.4064 1.2192)
			(layers "B.Cu" "B.Mask" "B.Paste")
			(net "P3V3_STBY")
		)
	)
	(footprint ""
		(layer "B.Cu")
		(at 20.955 -139.827 -90)
		(property "Reference" "R647"
			(at 0 0 90)
			(layer "B.SilkS")
			(hide yes)
			(effects
				(font
					(size 1.27 1.27)
				)
				(justify mirror)
			)
		)
		(property "Value" "0R2J-2-GP"
			(at -0.064008 -3.993896 270)
			(unlocked yes)
			(layer "B.Fab")
			(hide yes)
			(effects
				(font
					(size 1.016 1.016)
					(thickness 0.1524)
				)
				(justify mirror)
			)
		)
		(property "Device Type" "R402H16"
			(at -0.064008 -5.517896 270)
			(unlocked yes)
			(layer "B.Fab")
			(hide yes)
			(effects
				(font
					(size 1.016 1.016)
					(thickness 0.1524)
				)
				(justify mirror)
			)
		)
		(duplicate_pad_numbers_are_jumpers no)
		(fp_line
			(start -0.508 -0.9398)
			(end 0.508 -0.9398)
			(stroke
				(width 0.1524)
				(type default)
			)
			(layer "B.SilkS")
		)
		(fp_line
			(start 0.508 -0.9398)
			(end 0.508 0.9398)
			(stroke
				(width 0.1524)
				(type default)
			)
			(layer "B.SilkS")
		)
		(fp_rect
			(start 0.508 0.9398)
			(end -0.508 -0.9398)
			(stroke
				(width 0)
				(type default)
			)
			(fill no)
			(layer "B.CrtYd")
		)
		(fp_rect
			(start 0.508 0.9398)
			(end -0.508 -0.9398)
			(stroke
				(width 0)
				(type default)
			)
			(fill no)
			(layer "B.Fab")
		)
		(pad "1" smd custom
			(at 0 -0.4445 90)
			(size 0.1397 0.1397)
			(layers "B.Cu" "B.Mask" "B.Paste")
			(net "FLA_CS1")
			(options
				(clearance outline)
				(anchor circle)
			)
			(primitives
				(gr_poly
					(pts
						(arc
							(start -0.1778 0.2794)
							(mid -0.249642 0.249642)
							(end -0.2794 0.1778)
						)
						(arc
							(start -0.2794 -0.1778)
							(mid -0.249642 -0.249642)
							(end -0.1778 -0.2794)
						)
						(arc
							(start 0.1778 -0.2794)
							(mid 0.249642 -0.249642)
							(end 0.2794 -0.1778)
						)
						(arc
							(start 0.2794 0.1778)
							(mid 0.249642 0.249642)
							(end 0.1778 0.2794)
						)
					)
					(width 0)
					(fill yes)
				)
			)
		)
		(pad "2" smd custom
			(at 0 0.4445 90)
			(size 0.1397 0.1397)
			(layers "B.Cu" "B.Mask" "B.Paste")
			(net "FLA_CS1_R")
			(options
				(clearance outline)
				(anchor circle)
			)
			(primitives
				(gr_poly
					(pts
						(arc
							(start -0.1778 0.2794)
							(mid -0.249642 0.249642)
							(end -0.2794 0.1778)
						)
						(arc
							(start -0.2794 -0.1778)
							(mid -0.249642 -0.249642)
							(end -0.1778 -0.2794)
						)
						(arc
							(start 0.1778 -0.2794)
							(mid 0.249642 -0.249642)
							(end 0.2794 -0.1778)
						)
						(arc
							(start 0.2794 0.1778)
							(mid 0.249642 0.249642)
							(end 0.1778 0.2794)
						)
					)
					(width 0)
					(fill yes)
				)
			)
		)
	)
	(footprint ""
		(layer "B.Cu")
		(at 44.098972 -131.287774)
		(property "Reference" "TP317"
			(at 0 0 0)
			(layer "B.SilkS")
			(hide yes)
			(effects
				(font
					(size 1.27 1.27)
				)
				(justify mirror)
			)
		)
		(property "Value" "TPAD28-2-GP"
			(at 0.0127 -1.6637 0)
			(unlocked yes)
			(layer "B.Fab")
			(hide yes)
			(effects
				(font
					(size 1.016 1.016)
					(thickness 0.1524)
				)
				(justify mirror)
			)
		)
		(property "Device Type" "TPAD28"
			(at 0.0127 -3.1877 0)
			(unlocked yes)
			(layer "B.Fab")
			(hide yes)
			(effects
				(font
					(size 1.016 1.016)
					(thickness 0.1524)
				)
				(justify mirror)
			)
		)
		(duplicate_pad_numbers_are_jumpers no)
		(fp_poly
			(pts
				(arc
					(start 0.3556 0)
					(mid -0.3556 0)
					(end 0.3556 0)
				)
			)
			(stroke
				(width 0)
				(type default)
			)
			(fill no)
			(layer "B.CrtYd")
		)
		(fp_poly
			(pts
				(arc
					(start 0.6096 0)
					(mid -0.6096 0)
					(end 0.6096 0)
				)
			)
			(stroke
				(width 0)
				(type default)
			)
			(fill no)
			(layer "B.Fab")
		)
		(pad "1" smd circle
			(at 0 0 180)
			(size 0.7112 0.7112)
			(layers "B.Cu" "B.Mask" "B.Paste")
			(net "DACB")
		)
	)
	(footprint ""
		(layer "B.Cu")
		(at 233.68 -20.447)
		(property "Reference" "R817"
			(at 0 0 0)
			(layer "B.SilkS")
			(hide yes)
			(effects
				(font
					(size 1.27 1.27)
				)
				(justify mirror)
			)
		)
		(property "Value" "4K7R2F-GP"
			(at -0.064008 -3.993896 0)
			(unlocked yes)
			(layer "B.Fab")
			(hide yes)
			(effects
				(font
					(size 1.016 1.016)
					(thickness 0.1524)
				)
				(justify mirror)
			)
		)
		(property "Device Type" "R402H16"
			(at -0.064008 -5.517896 0)
			(unlocked yes)
			(layer "B.Fab")
			(hide yes)
			(effects
				(font
					(size 1.016 1.016)
					(thickness 0.1524)
				)
				(justify mirror)
			)
		)
		(duplicate_pad_numbers_are_jumpers no)
		(fp_line
			(start -0.508 -0.9398)
			(end 0.508 -0.9398)
			(stroke
				(width 0.1524)
				(type default)
			)
			(layer "B.SilkS")
		)
		(fp_line
			(start 0.508 -0.9398)
			(end 0.508 0.9398)
			(stroke
				(width 0.1524)
				(type default)
			)
			(layer "B.SilkS")
		)
		(fp_rect
			(start 0.508 0.9398)
			(end -0.508 -0.9398)
			(stroke
				(width 0)
				(type default)
			)
			(fill no)
			(layer "B.CrtYd")
		)
		(fp_rect
			(start 0.508 0.9398)
			(end -0.508 -0.9398)
			(stroke
				(width 0)
				(type default)
			)
			(fill no)
			(layer "B.Fab")
		)
		(pad "1" smd custom
			(at 0 -0.4445 180)
			(size 0.1397 0.1397)
			(layers "B.Cu" "B.Mask" "B.Paste")
			(net "BOOTSTRAP8")
			(options
				(clearance outline)
				(anchor circle)
			)
			(primitives
				(gr_poly
					(pts
						(arc
							(start -0.1778 0.2794)
							(mid -0.249642 0.249642)
							(end -0.2794 0.1778)
						)
						(arc
							(start -0.2794 -0.1778)
							(mid -0.249642 -0.249642)
							(end -0.1778 -0.2794)
						)
						(arc
							(start 0.1778 -0.2794)
							(mid 0.249642 -0.249642)
							(end 0.2794 -0.1778)
						)
						(arc
							(start 0.2794 0.1778)
							(mid 0.249642 0.249642)
							(end 0.1778 0.2794)
						)
					)
					(width 0)
					(fill yes)
				)
			)
		)
		(pad "2" smd custom
			(at 0 0.4445 180)
			(size 0.1397 0.1397)
			(layers "B.Cu" "B.Mask" "B.Paste")
			(net "DUT_VDDO")
			(options
				(clearance outline)
				(anchor circle)
			)
			(primitives
				(gr_poly
					(pts
						(arc
							(start -0.1778 0.2794)
							(mid -0.249642 0.249642)
							(end -0.2794 0.1778)
						)
						(arc
							(start -0.2794 -0.1778)
							(mid -0.249642 -0.249642)
							(end -0.1778 -0.2794)
						)
						(arc
							(start 0.1778 -0.2794)
							(mid 0.249642 -0.249642)
							(end 0.2794 -0.1778)
						)
						(arc
							(start 0.2794 0.1778)
							(mid 0.249642 0.249642)
							(end 0.1778 0.2794)
						)
					)
					(width 0)
					(fill yes)
				)
			)
		)
	)
	(footprint ""
		(layer "B.Cu")
		(at 228.6254 -54.995572 90)
		(property "Reference" "C537"
			(at 0 0 90)
			(layer "B.SilkS")
			(hide yes)
			(effects
				(font
					(size 1.27 1.27)
				)
				(justify mirror)
			)
		)
		(property "Value" "SCD1U16V1KX-1-GP"
			(at 2.8321 -1.7399 90)
			(unlocked yes)
			(layer "B.Fab")
			(hide yes)
			(effects
				(font
					(size 1.016 1.016)
					(thickness 0.1524)
				)
				(justify mirror)
			)
		)
		(property "Device Type" "C0201H13"
			(at 2.8321 -3.2639 90)
			(unlocked yes)
			(layer "B.Fab")
			(hide yes)
			(effects
				(font
					(size 1.016 1.016)
					(thickness 0.1524)
				)
				(justify mirror)
			)
		)
		(duplicate_pad_numbers_are_jumpers no)
		(fp_rect
			(start 0.2794 0.6477)
			(end -0.2794 -0.6477)
			(stroke
				(width 0)
				(type default)
			)
			(fill no)
			(layer "B.CrtYd")
		)
		(fp_rect
			(start 0.2794 0.6477)
			(end -0.2794 -0.6477)
			(stroke
				(width 0)
				(type default)
			)
			(fill no)
			(layer "B.Fab")
		)
		(pad "1" smd custom
			(at 0 -0.2794 270)
			(size 0.0762 0.0762)
			(layers "B.Cu" "B.Mask" "B.Paste")
			(net "DUT_AVD_PCIE")
			(options
				(clearance outline)
				(anchor circle)
			)
			(primitives
				(gr_poly
					(pts
						(arc
							(start 0.1524 0.127)
							(mid 0.137521 0.162921)
							(end 0.1016 0.1778)
						)
						(arc
							(start -0.1016 0.1778)
							(mid -0.137521 0.162921)
							(end -0.1524 0.127)
						)
						(arc
							(start -0.1524 -0.127)
							(mid -0.137521 -0.162921)
							(end -0.1016 -0.1778)
						)
						(arc
							(start 0.1016 -0.1778)
							(mid 0.137521 -0.162921)
							(end 0.1524 -0.127)
						)
					)
					(width 0)
					(fill yes)
				)
			)
		)
		(pad "2" smd custom
			(at 0 0.2794 270)
			(size 0.0762 0.0762)
			(layers "B.Cu" "B.Mask" "B.Paste")
			(net "GND")
			(options
				(clearance outline)
				(anchor circle)
			)
			(primitives
				(gr_poly
					(pts
						(arc
							(start 0.1524 0.127)
							(mid 0.137521 0.162921)
							(end 0.1016 0.1778)
						)
						(arc
							(start -0.1016 0.1778)
							(mid -0.137521 0.162921)
							(end -0.1524 0.127)
						)
						(arc
							(start -0.1524 -0.127)
							(mid -0.137521 -0.162921)
							(end -0.1016 -0.1778)
						)
						(arc
							(start 0.1016 -0.1778)
							(mid 0.137521 -0.162921)
							(end 0.1524 -0.127)
						)
					)
					(width 0)
					(fill yes)
				)
			)
		)
	)
	(footprint ""
		(layer "B.Cu")
		(at 57.023 -141.859 -90)
		(property "Reference" "R584"
			(at 0 0 90)
			(layer "B.SilkS")
			(hide yes)
			(effects
				(font
					(size 1.27 1.27)
				)
				(justify mirror)
			)
		)
		(property "Value" "0R2J-2-GP"
			(at -0.064008 -3.993896 270)
			(unlocked yes)
			(layer "B.Fab")
			(hide yes)
			(effects
				(font
					(size 1.016 1.016)
					(thickness 0.1524)
				)
				(justify mirror)
			)
		)
		(property "Device Type" "R402H16"
			(at -0.064008 -5.517896 270)
			(unlocked yes)
			(layer "B.Fab")
			(hide yes)
			(effects
				(font
					(size 1.016 1.016)
					(thickness 0.1524)
				)
				(justify mirror)
			)
		)
		(duplicate_pad_numbers_are_jumpers no)
		(fp_line
			(start -0.508 -0.9398)
			(end 0.508 -0.9398)
			(stroke
				(width 0.1524)
				(type default)
			)
			(layer "B.SilkS")
		)
		(fp_line
			(start 0.508 -0.9398)
			(end 0.508 0.9398)
			(stroke
				(width 0.1524)
				(type default)
			)
			(layer "B.SilkS")
		)
		(fp_rect
			(start 0.508 0.9398)
			(end -0.508 -0.9398)
			(stroke
				(width 0)
				(type default)
			)
			(fill no)
			(layer "B.CrtYd")
		)
		(fp_rect
			(start 0.508 0.9398)
			(end -0.508 -0.9398)
			(stroke
				(width 0)
				(type default)
			)
			(fill no)
			(layer "B.Fab")
		)
		(pad "1" smd custom
			(at 0 -0.4445 90)
			(size 0.1397 0.1397)
			(layers "B.Cu" "B.Mask" "B.Paste")
			(net "UART_COUNT")
			(options
				(clearance outline)
				(anchor circle)
			)
			(primitives
				(gr_poly
					(pts
						(arc
							(start -0.1778 0.2794)
							(mid -0.249642 0.249642)
							(end -0.2794 0.1778)
						)
						(arc
							(start -0.2794 -0.1778)
							(mid -0.249642 -0.249642)
							(end -0.1778 -0.2794)
						)
						(arc
							(start 0.1778 -0.2794)
							(mid 0.249642 -0.249642)
							(end 0.2794 -0.1778)
						)
						(arc
							(start 0.2794 0.1778)
							(mid 0.249642 0.249642)
							(end 0.1778 0.2794)
						)
					)
					(width 0)
					(fill yes)
				)
			)
		)
		(pad "2" smd custom
			(at 0 0.4445 90)
			(size 0.1397 0.1397)
			(layers "B.Cu" "B.Mask" "B.Paste")
			(net "BMC0_TACH13")
			(options
				(clearance outline)
				(anchor circle)
			)
			(primitives
				(gr_poly
					(pts
						(arc
							(start -0.1778 0.2794)
							(mid -0.249642 0.249642)
							(end -0.2794 0.1778)
						)
						(arc
							(start -0.2794 -0.1778)
							(mid -0.249642 -0.249642)
							(end -0.1778 -0.2794)
						)
						(arc
							(start 0.1778 -0.2794)
							(mid 0.249642 -0.249642)
							(end 0.2794 -0.1778)
						)
						(arc
							(start 0.2794 0.1778)
							(mid 0.249642 0.249642)
							(end 0.1778 0.2794)
						)
					)
					(width 0)
					(fill yes)
				)
			)
		)
	)
)
